(kicad_pcb
	(version 20260206)
	(generator "pcbnew")
	(generator_version "10.0")
	(general
		(thickness 1.6)
		(legacy_teardrops no)
	)
	(paper "A4")
	(title_block
		(title "03242023_DA0F0TMBIJ0_F0T_Motherboard_J_brd_V01_OCP.brd")
		(comment 1 "Grand Teton / footprints 3962-3969 of 6105")
	)
	(layers
		(0 "F.Cu" signal "TOP")
		(4 "In1.Cu" signal "GND")
		(6 "In2.Cu" signal "IN1")
		(8 "In3.Cu" signal "GND1")
		(10 "In4.Cu" signal "IN2")
		(12 "In5.Cu" signal "GND2")
		(14 "In6.Cu" signal "IN3")
		(16 "In7.Cu" signal "GND3")
		(18 "In8.Cu" signal "VCC")
		(20 "In9.Cu" signal "VCC1")
		(22 "In10.Cu" signal "GND4")
		(24 "In11.Cu" signal "IN4")
		(26 "In12.Cu" signal "GND5")
		(28 "In13.Cu" signal "IN5")
		(30 "In14.Cu" signal "GND6")
		(32 "In15.Cu" signal "IN6")
		(34 "In16.Cu" signal "GND7")
		(2 "B.Cu" signal "BOTTOM")
		(9 "F.Adhes" user "F.Adhesive")
		(11 "B.Adhes" user "B.Adhesive")
		(13 "F.Paste" user "Package Geometry/Pastemask Top")
		(15 "B.Paste" user "Package Geometry/Pastemask Bottom")
		(5 "F.SilkS" user "Ref Des/Silkscreen Top")
		(7 "B.SilkS" user "Ref Des/Silkscreen Bottom")
		(1 "F.Mask" user "Board Geometry/Soldermask Top")
		(3 "B.Mask" user "Board Geometry/Soldermask Bottom")
		(17 "Dwgs.User" user "User.Drawings")
		(19 "Cmts.User" user "User.Comments")
		(21 "Eco1.User" user "User.Eco1")
		(23 "Eco2.User" user "User.Eco2")
		(25 "Edge.Cuts" user "Board Geometry/Outline")
		(27 "Margin" user)
		(31 "F.CrtYd" user "Package Geometry/Place Bound Top")
		(29 "B.CrtYd" user "Package Geometry/Place Bound Bottom")
		(35 "F.Fab" user "Ref Des/Assembly Top")
		(33 "B.Fab" user "Ref Des/Assembly Bottom")
	)
	(footprint ""
		(layer "F.Cu")
		(at 298.66082 -419.02761 -90)
		(property "Reference" "C2268"
			(at 0 0 270)
			(layer "F.SilkS")
			(hide yes)
			(effects
				(font
					(size 1.27 1.27)
				)
			)
		)
		(property "Value" ""
			(at 0 0 270)
			(layer "F.Fab")
			(effects
				(font
					(size 1.27 1.27)
				)
			)
		)
		(duplicate_pad_numbers_are_jumpers no)
		(fp_line
			(start -0.7874 0.4064)
			(end -0.7874 -0.4064)
			(stroke
				(width 0.1524)
				(type default)
			)
			(layer "F.SilkS")
		)
		(fp_line
			(start 0.7874 0.4064)
			(end -0.7874 0.4064)
			(stroke
				(width 0.1524)
				(type default)
			)
			(layer "F.SilkS")
		)
		(fp_line
			(start -0.7874 -0.4064)
			(end 0.7874 -0.4064)
			(stroke
				(width 0.1524)
				(type default)
			)
			(layer "F.SilkS")
		)
		(fp_line
			(start 0.7874 -0.4064)
			(end 0.7874 0.4064)
			(stroke
				(width 0.1524)
				(type default)
			)
			(layer "F.SilkS")
		)
		(fp_line
			(start -0.67945 0.3048)
			(end -0.67945 -0.305054)
			(stroke
				(width 0.1)
				(type default)
			)
			(layer "F.Fab")
		)
		(fp_line
			(start -0.12065 0.3048)
			(end -0.67945 0.3048)
			(stroke
				(width 0.1)
				(type default)
			)
			(layer "F.Fab")
		)
		(fp_line
			(start 0.120396 0.3048)
			(end 0.120396 0.2794)
			(stroke
				(width 0.1)
				(type default)
			)
			(layer "F.Fab")
		)
		(fp_line
			(start 0.67945 0.3048)
			(end 0.120396 0.3048)
			(stroke
				(width 0.1)
				(type default)
			)
			(layer "F.Fab")
		)
		(fp_line
			(start -0.12065 0.2794)
			(end -0.12065 0.3048)
			(stroke
				(width 0.1)
				(type default)
			)
			(layer "F.Fab")
		)
		(fp_line
			(start 0.120396 0.2794)
			(end -0.12065 0.2794)
			(stroke
				(width 0.1)
				(type default)
			)
			(layer "F.Fab")
		)
		(fp_line
			(start -0.12065 -0.2794)
			(end 0.12065 -0.2794)
			(stroke
				(width 0.1)
				(type default)
			)
			(layer "F.Fab")
		)
		(fp_line
			(start 0.12065 -0.2794)
			(end 0.12065 -0.3048)
			(stroke
				(width 0.1)
				(type default)
			)
			(layer "F.Fab")
		)
		(fp_line
			(start 0.12065 -0.3048)
			(end 0.67945 -0.3048)
			(stroke
				(width 0.1)
				(type default)
			)
			(layer "F.Fab")
		)
		(fp_line
			(start 0.67945 -0.3048)
			(end 0.67945 0.3048)
			(stroke
				(width 0.1)
				(type default)
			)
			(layer "F.Fab")
		)
		(fp_line
			(start -0.67945 -0.305054)
			(end -0.12065 -0.305054)
			(stroke
				(width 0.1)
				(type default)
			)
			(layer "F.Fab")
		)
		(fp_line
			(start -0.12065 -0.305054)
			(end -0.12065 -0.2794)
			(stroke
				(width 0.1)
				(type default)
			)
			(layer "F.Fab")
		)
		(pad "1" smd circle
			(at -0.40005 0 270)
			(size 0 0)
			(layers "F.Cu" "F.Mask" "F.Paste")
			(net "GPU_3V3IO_RSVD5_FFU_ISO")
		)
		(pad "2" smd circle
			(at 0.40005 0 270)
			(size 0 0)
			(layers "F.Cu" "F.Mask" "F.Paste")
			(net "GND")
		)
	)
	(footprint ""
		(layer "F.Cu")
		(at 80.795876 -79.078836)
		(property "Reference" "D80"
			(at -41.50741 34.331402 90)
			(unlocked yes)
			(layer "F.SilkS")
			(effects
				(font
					(size 0.635 0.4064)
					(thickness 0.1524)
				)
				(justify left)
			)
		)
		(property "Value" ""
			(at 0 0 0)
			(layer "F.Fab")
			(effects
				(font
					(size 1.27 1.27)
				)
			)
		)
		(duplicate_pad_numbers_are_jumpers no)
		(fp_line
			(start -0.90678 0.4826)
			(end -0.90678 -0.4699)
			(stroke
				(width 0.1524)
				(type default)
			)
			(layer "F.SilkS")
		)
		(fp_line
			(start -0.89408 -0.4826)
			(end 0.90678 -0.4826)
			(stroke
				(width 0.1524)
				(type default)
			)
			(layer "F.SilkS")
		)
		(fp_line
			(start -0.79248 -0.4826)
			(end 1.03378 -0.4826)
			(stroke
				(width 0.1524)
				(type default)
			)
			(layer "F.SilkS")
		)
		(fp_line
			(start -0.64008 -0.4826)
			(end 1.16078 -0.4826)
			(stroke
				(width 0.1524)
				(type default)
			)
			(layer "F.SilkS")
		)
		(fp_line
			(start 0.90678 -0.4826)
			(end 0.90678 0.4826)
			(stroke
				(width 0.1524)
				(type default)
			)
			(layer "F.SilkS")
		)
		(fp_line
			(start 0.90678 0.4826)
			(end -0.90678 0.4826)
			(stroke
				(width 0.1524)
				(type default)
			)
			(layer "F.SilkS")
		)
		(fp_line
			(start 1.03378 -0.4826)
			(end 1.03378 0.4826)
			(stroke
				(width 0.1524)
				(type default)
			)
			(layer "F.SilkS")
		)
		(fp_line
			(start 1.03378 0.4826)
			(end -0.79248 0.4826)
			(stroke
				(width 0.1524)
				(type default)
			)
			(layer "F.SilkS")
		)
		(fp_line
			(start 1.16078 -0.4826)
			(end 1.16078 0.4826)
			(stroke
				(width 0.1524)
				(type default)
			)
			(layer "F.SilkS")
		)
		(fp_line
			(start 1.16078 0.4826)
			(end -0.64008 0.4826)
			(stroke
				(width 0.1524)
				(type default)
			)
			(layer "F.SilkS")
		)
		(fp_line
			(start -0.499872 -0.249936)
			(end 0.499872 -0.249936)
			(stroke
				(width 0.1)
				(type default)
			)
			(layer "F.Fab")
		)
		(fp_line
			(start -0.499872 0.249936)
			(end -0.499872 -0.249936)
			(stroke
				(width 0.1)
				(type default)
			)
			(layer "F.Fab")
		)
		(fp_line
			(start 0.499872 -0.249936)
			(end 0.499872 0.249936)
			(stroke
				(width 0.1)
				(type default)
			)
			(layer "F.Fab")
		)
		(fp_line
			(start 0.499872 0.249936)
			(end -0.499872 0.249936)
			(stroke
				(width 0.1)
				(type default)
			)
			(layer "F.Fab")
		)
		(pad "A" smd rect
			(at -0.47498 0)
			(size 0.6096 0.7112)
			(layers "F.Cu" "F.Mask" "F.Paste")
			(net "LED_PWRGD_PVCCD_HV_CPU1")
		)
		(pad "C" smd rect
			(at 0.47498 0)
			(size 0.6096 0.7112)
			(layers "F.Cu" "F.Mask" "F.Paste")
			(net "LED_PWRGD_PVCCD_HV_CPU1_D")
		)
	)
	(footprint ""
		(layer "F.Cu")
		(at 429.183038 -181.53507 90)
		(property "Reference" "PC1272"
			(at 0 0 90)
			(layer "F.SilkS")
			(hide yes)
			(effects
				(font
					(size 1.27 1.27)
				)
			)
		)
		(property "Value" ""
			(at 0 0 90)
			(layer "F.Fab")
			(effects
				(font
					(size 1.27 1.27)
				)
			)
		)
		(duplicate_pad_numbers_are_jumpers no)
		(fp_line
			(start 1.524 -0.762)
			(end 1.524 0.762)
			(stroke
				(width 0.1524)
				(type default)
			)
			(layer "F.SilkS")
		)
		(fp_line
			(start -1.524 -0.762)
			(end 1.524 -0.762)
			(stroke
				(width 0.1524)
				(type default)
			)
			(layer "F.SilkS")
		)
		(fp_line
			(start 1.524 0.762)
			(end -1.524 0.762)
			(stroke
				(width 0.1524)
				(type default)
			)
			(layer "F.SilkS")
		)
		(fp_line
			(start -1.524 0.762)
			(end -1.524 -0.762)
			(stroke
				(width 0.1524)
				(type default)
			)
			(layer "F.SilkS")
		)
		(fp_line
			(start 1.1049 -0.724916)
			(end -1.1049 -0.724916)
			(stroke
				(width 0.1)
				(type default)
			)
			(layer "F.Fab")
		)
		(fp_line
			(start -1.1049 -0.724916)
			(end -1.1049 0.724916)
			(stroke
				(width 0.1)
				(type default)
			)
			(layer "F.Fab")
		)
		(fp_line
			(start 1.1049 0.724916)
			(end 1.1049 -0.724916)
			(stroke
				(width 0.1)
				(type default)
			)
			(layer "F.Fab")
		)
		(fp_line
			(start -1.1049 0.724916)
			(end 1.1049 0.724916)
			(stroke
				(width 0.1)
				(type default)
			)
			(layer "F.Fab")
		)
		(pad "1" smd rect
			(at -0.889 0 270)
			(size 1.016 1.27)
			(layers "F.Cu" "F.Mask" "F.Paste")
			(net "SW_P12V_PVCCINFAON_CPU0_FLT")
		)
		(pad "2" smd rect
			(at 0.889 0 270)
			(size 1.016 1.27)
			(layers "F.Cu" "F.Mask" "F.Paste")
			(net "GND")
		)
	)
	(footprint ""
		(layer "F.Cu")
		(at 349.903288 -402.371052 -90)
		(property "Reference" "C1548"
			(at 0 0 270)
			(layer "F.SilkS")
			(hide yes)
			(effects
				(font
					(size 1.27 1.27)
				)
			)
		)
		(property "Value" ""
			(at 0 0 270)
			(layer "F.Fab")
			(effects
				(font
					(size 1.27 1.27)
				)
			)
		)
		(duplicate_pad_numbers_are_jumpers no)
		(fp_line
			(start -0.299974 0.150114)
			(end -0.299974 -0.150114)
			(stroke
				(width 0.1)
				(type default)
			)
			(layer "F.Fab")
		)
		(fp_line
			(start 0.299974 0.150114)
			(end -0.299974 0.150114)
			(stroke
				(width 0.1)
				(type default)
			)
			(layer "F.Fab")
		)
		(fp_line
			(start -0.299974 -0.150114)
			(end 0.299974 -0.150114)
			(stroke
				(width 0.1)
				(type default)
			)
			(layer "F.Fab")
		)
		(fp_line
			(start 0.299974 -0.150114)
			(end 0.299974 0.150114)
			(stroke
				(width 0.1)
				(type default)
			)
			(layer "F.Fab")
		)
		(pad "1" smd rect
			(at -0.2667 0 270)
			(size 0.3048 0.381)
			(layers "F.Cu" "F.Mask" "F.Paste")
			(net "P5E_CPU0_PE4_TX_C_DN<15>")
		)
		(pad "2" smd rect
			(at 0.2667 0 270)
			(size 0.3048 0.381)
			(layers "F.Cu" "F.Mask" "F.Paste")
			(net "P5E_CPU0_PE4_TX_DN<15>")
		)
	)
	(footprint ""
		(layer "F.Cu")
		(at 99.999546 -356.625652 -90)
		(property "Reference" "C2449"
			(at 0 0 270)
			(layer "F.SilkS")
			(hide yes)
			(effects
				(font
					(size 1.27 1.27)
				)
			)
		)
		(property "Value" ""
			(at 0 0 270)
			(layer "F.Fab")
			(effects
				(font
					(size 1.27 1.27)
				)
			)
		)
		(duplicate_pad_numbers_are_jumpers no)
		(fp_line
			(start -0.7874 0.4064)
			(end -0.7874 -0.4064)
			(stroke
				(width 0.1524)
				(type default)
			)
			(layer "F.SilkS")
		)
		(fp_line
			(start 0.7874 0.4064)
			(end -0.7874 0.4064)
			(stroke
				(width 0.1524)
				(type default)
			)
			(layer "F.SilkS")
		)
		(fp_line
			(start -0.7874 -0.4064)
			(end 0.7874 -0.4064)
			(stroke
				(width 0.1524)
				(type default)
			)
			(layer "F.SilkS")
		)
		(fp_line
			(start 0.7874 -0.4064)
			(end 0.7874 0.4064)
			(stroke
				(width 0.1524)
				(type default)
			)
			(layer "F.SilkS")
		)
		(fp_line
			(start -0.67945 0.3048)
			(end -0.67945 -0.305054)
			(stroke
				(width 0.1)
				(type default)
			)
			(layer "F.Fab")
		)
		(fp_line
			(start -0.12065 0.3048)
			(end -0.67945 0.3048)
			(stroke
				(width 0.1)
				(type default)
			)
			(layer "F.Fab")
		)
		(fp_line
			(start 0.120396 0.3048)
			(end 0.120396 0.2794)
			(stroke
				(width 0.1)
				(type default)
			)
			(layer "F.Fab")
		)
		(fp_line
			(start 0.67945 0.3048)
			(end 0.120396 0.3048)
			(stroke
				(width 0.1)
				(type default)
			)
			(layer "F.Fab")
		)
		(fp_line
			(start -0.12065 0.2794)
			(end -0.12065 0.3048)
			(stroke
				(width 0.1)
				(type default)
			)
			(layer "F.Fab")
		)
		(fp_line
			(start 0.120396 0.2794)
			(end -0.12065 0.2794)
			(stroke
				(width 0.1)
				(type default)
			)
			(layer "F.Fab")
		)
		(fp_line
			(start -0.12065 -0.2794)
			(end 0.12065 -0.2794)
			(stroke
				(width 0.1)
				(type default)
			)
			(layer "F.Fab")
		)
		(fp_line
			(start 0.12065 -0.2794)
			(end 0.12065 -0.3048)
			(stroke
				(width 0.1)
				(type default)
			)
			(layer "F.Fab")
		)
		(fp_line
			(start 0.12065 -0.3048)
			(end 0.67945 -0.3048)
			(stroke
				(width 0.1)
				(type default)
			)
			(layer "F.Fab")
		)
		(fp_line
			(start 0.67945 -0.3048)
			(end 0.67945 0.3048)
			(stroke
				(width 0.1)
				(type default)
			)
			(layer "F.Fab")
		)
		(fp_line
			(start -0.67945 -0.305054)
			(end -0.12065 -0.305054)
			(stroke
				(width 0.1)
				(type default)
			)
			(layer "F.Fab")
		)
		(fp_line
			(start -0.12065 -0.305054)
			(end -0.12065 -0.2794)
			(stroke
				(width 0.1)
				(type default)
			)
			(layer "F.Fab")
		)
		(pad "1" smd circle
			(at -0.40005 0 270)
			(size 0 0)
			(layers "F.Cu" "F.Mask" "F.Paste")
			(net "PVNN_TERM_CPU1")
		)
		(pad "2" smd circle
			(at 0.40005 0 270)
			(size 0 0)
			(layers "F.Cu" "F.Mask" "F.Paste")
			(net "GND")
		)
	)
	(footprint ""
		(layer "F.Cu")
		(at 432.41468 -174.78502)
		(property "Reference" "PC237"
			(at 0 0 0)
			(layer "F.SilkS")
			(hide yes)
			(effects
				(font
					(size 1.27 1.27)
				)
			)
		)
		(property "Value" ""
			(at 0 0 0)
			(layer "F.Fab")
			(effects
				(font
					(size 1.27 1.27)
				)
			)
		)
		(duplicate_pad_numbers_are_jumpers no)
		(fp_line
			(start -0.7874 -0.4064)
			(end 0.7874 -0.4064)
			(stroke
				(width 0.1524)
				(type default)
			)
			(layer "F.SilkS")
		)
		(fp_line
			(start -0.7874 0.4064)
			(end -0.7874 -0.4064)
			(stroke
				(width 0.1524)
				(type default)
			)
			(layer "F.SilkS")
		)
		(fp_line
			(start 0.7874 -0.4064)
			(end 0.7874 0.4064)
			(stroke
				(width 0.1524)
				(type default)
			)
			(layer "F.SilkS")
		)
		(fp_line
			(start 0.7874 0.4064)
			(end -0.7874 0.4064)
			(stroke
				(width 0.1524)
				(type default)
			)
			(layer "F.SilkS")
		)
		(fp_line
			(start -0.67945 -0.305054)
			(end -0.12065 -0.305054)
			(stroke
				(width 0.1)
				(type default)
			)
			(layer "F.Fab")
		)
		(fp_line
			(start -0.67945 0.3048)
			(end -0.67945 -0.305054)
			(stroke
				(width 0.1)
				(type default)
			)
			(layer "F.Fab")
		)
		(fp_line
			(start -0.12065 -0.305054)
			(end -0.12065 -0.2794)
			(stroke
				(width 0.1)
				(type default)
			)
			(layer "F.Fab")
		)
		(fp_line
			(start -0.12065 -0.2794)
			(end 0.12065 -0.2794)
			(stroke
				(width 0.1)
				(type default)
			)
			(layer "F.Fab")
		)
		(fp_line
			(start -0.12065 0.2794)
			(end -0.12065 0.3048)
			(stroke
				(width 0.1)
				(type default)
			)
			(layer "F.Fab")
		)
		(fp_line
			(start -0.12065 0.3048)
			(end -0.67945 0.3048)
			(stroke
				(width 0.1)
				(type default)
			)
			(layer "F.Fab")
		)
		(fp_line
			(start 0.120396 0.2794)
			(end -0.12065 0.2794)
			(stroke
				(width 0.1)
				(type default)
			)
			(layer "F.Fab")
		)
		(fp_line
			(start 0.120396 0.3048)
			(end 0.120396 0.2794)
			(stroke
				(width 0.1)
				(type default)
			)
			(layer "F.Fab")
		)
		(fp_line
			(start 0.12065 -0.3048)
			(end 0.67945 -0.3048)
			(stroke
				(width 0.1)
				(type default)
			)
			(layer "F.Fab")
		)
		(fp_line
			(start 0.12065 -0.2794)
			(end 0.12065 -0.3048)
			(stroke
				(width 0.1)
				(type default)
			)
			(layer "F.Fab")
		)
		(fp_line
			(start 0.67945 -0.3048)
			(end 0.67945 0.3048)
			(stroke
				(width 0.1)
				(type default)
			)
			(layer "F.Fab")
		)
		(fp_line
			(start 0.67945 0.3048)
			(end 0.120396 0.3048)
			(stroke
				(width 0.1)
				(type default)
			)
			(layer "F.Fab")
		)
		(pad "1" smd circle
			(at -0.40005 0)
			(size 0 0)
			(layers "F.Cu" "F.Mask" "F.Paste")
			(net "PVNN_MAIN_CPU0_FB")
		)
		(pad "2" smd circle
			(at 0.40005 0)
			(size 0 0)
			(layers "F.Cu" "F.Mask" "F.Paste")
			(net "PVNN_MAIN_CPU0_FB_RC")
		)
	)
	(footprint ""
		(layer "F.Cu")
		(at 151.676354 -402.371052 -90)
		(property "Reference" "C762"
			(at 0 0 270)
			(layer "F.SilkS")
			(hide yes)
			(effects
				(font
					(size 1.27 1.27)
				)
			)
		)
		(property "Value" ""
			(at 0 0 270)
			(layer "F.Fab")
			(effects
				(font
					(size 1.27 1.27)
				)
			)
		)
		(duplicate_pad_numbers_are_jumpers no)
		(fp_line
			(start -0.299974 0.150114)
			(end -0.299974 -0.150114)
			(stroke
				(width 0.1)
				(type default)
			)
			(layer "F.Fab")
		)
		(fp_line
			(start 0.299974 0.150114)
			(end -0.299974 0.150114)
			(stroke
				(width 0.1)
				(type default)
			)
			(layer "F.Fab")
		)
		(fp_line
			(start -0.299974 -0.150114)
			(end 0.299974 -0.150114)
			(stroke
				(width 0.1)
				(type default)
			)
			(layer "F.Fab")
		)
		(fp_line
			(start 0.299974 -0.150114)
			(end 0.299974 0.150114)
			(stroke
				(width 0.1)
				(type default)
			)
			(layer "F.Fab")
		)
		(pad "1" smd rect
			(at -0.2667 0 270)
			(size 0.3048 0.381)
			(layers "F.Cu" "F.Mask" "F.Paste")
			(net "P5E_CPU1_PE2_TX_C_DN<5>")
		)
		(pad "2" smd rect
			(at 0.2667 0 270)
			(size 0.3048 0.381)
			(layers "F.Cu" "F.Mask" "F.Paste")
			(net "P5E_CPU1_PE2_TX_DN<5>")
		)
	)
	(footprint ""
		(layer "F.Cu")
		(at 44.848018 -437.792368 180)
		(property "Reference" "R2992"
			(at 0 0 180)
			(layer "F.SilkS")
			(hide yes)
			(effects
				(font
					(size 1.27 1.27)
				)
			)
		)
		(property "Value" ""
			(at 0 0 180)
			(layer "F.Fab")
			(effects
				(font
					(size 1.27 1.27)
				)
			)
		)
		(duplicate_pad_numbers_are_jumpers no)
		(fp_line
			(start 0.7874 0.4064)
			(end -0.7874 0.4064)
			(stroke
				(width 0.1524)
				(type default)
			)
			(layer "F.SilkS")
		)
		(fp_line
			(start 0.7874 -0.4064)
			(end 0.7874 0.4064)
			(stroke
				(width 0.1524)
				(type default)
			)
			(layer "F.SilkS")
		)
		(fp_line
			(start -0.7874 0.4064)
			(end -0.7874 -0.4064)
			(stroke
				(width 0.1524)
				(type default)
			)
			(layer "F.SilkS")
		)
		(fp_line
			(start -0.7874 -0.4064)
			(end 0.7874 -0.4064)
			(stroke
				(width 0.1524)
				(type default)
			)
			(layer "F.SilkS")
		)
		(fp_line
			(start 0.67945 0.3048)
			(end 0.120396 0.3048)
			(stroke
				(width 0.1)
				(type default)
			)
			(layer "F.Fab")
		)
		(fp_line
			(start 0.67945 -0.3048)
			(end 0.67945 0.3048)
			(stroke
				(width 0.1)
				(type default)
			)
			(layer "F.Fab")
		)
		(fp_line
			(start 0.12065 -0.2794)
			(end 0.12065 -0.3048)
			(stroke
				(width 0.1)
				(type default)
			)
			(layer "F.Fab")
		)
		(fp_line
			(start 0.12065 -0.3048)
			(end 0.67945 -0.3048)
			(stroke
				(width 0.1)
				(type default)
			)
			(layer "F.Fab")
		)
		(fp_line
			(start 0.120396 0.3048)
			(end 0.120396 0.2794)
			(stroke
				(width 0.1)
				(type default)
			)
			(layer "F.Fab")
		)
		(fp_line
			(start 0.120396 0.2794)
			(end -0.12065 0.2794)
			(stroke
				(width 0.1)
				(type default)
			)
			(layer "F.Fab")
		)
		(fp_line
			(start -0.12065 0.3048)
			(end -0.67945 0.3048)
			(stroke
				(width 0.1)
				(type default)
			)
			(layer "F.Fab")
		)
		(fp_line
			(start -0.12065 0.2794)
			(end -0.12065 0.3048)
			(stroke
				(width 0.1)
				(type default)
			)
			(layer "F.Fab")
		)
		(fp_line
			(start -0.12065 -0.2794)
			(end 0.12065 -0.2794)
			(stroke
				(width 0.1)
				(type default)
			)
			(layer "F.Fab")
		)
		(fp_line
			(start -0.12065 -0.305054)
			(end -0.12065 -0.2794)
			(stroke
				(width 0.1)
				(type default)
			)
			(layer "F.Fab")
		)
		(fp_line
			(start -0.67945 0.3048)
			(end -0.67945 -0.305054)
			(stroke
				(width 0.1)
				(type default)
			)
			(layer "F.Fab")
		)
		(fp_line
			(start -0.67945 -0.305054)
			(end -0.12065 -0.305054)
			(stroke
				(width 0.1)
				(type default)
			)
			(layer "F.Fab")
		)
		(pad "1" smd circle
			(at -0.40005 0 180)
			(size 0 0)
			(layers "F.Cu" "F.Mask" "F.Paste")
			(net "SMB_BMC_GPU_EN")
		)
		(pad "2" smd circle
			(at 0.40005 0 180)
			(size 0 0)
			(layers "F.Cu" "F.Mask" "F.Paste")
			(net "SMB_BMC_GPU_EN_R3")
		)
	)
)
